# S9S_MB_2U (Grand Teton) — schematic netlist excerpt (pin names and nets, part order shuffled) for the footprints in the layout excerpt that follows; sources: Cadence DE-HDL packaged netlist, KiCad conversion of 03242023_DA0F0TMBIJ0_F0T_Motherboard_J_brd_V01_OCP.brd

R414  Q_RES  4.7K 1% EMPTY  pkg 0402LF  page 153 : A = P3V3_OCP_SFF ; B = OCP_SFF_ID1
R198  Q_RES  301 1% CHIP  pkg 0402LF  page 123 : A = PVNN_TERM_CPU1 ; B = H_CPU1_NMI_LVC1_N

(kicad_pcb
	(version 20260206)
	(generator "pcbnew")
	(generator_version "10.0")
	(general
		(thickness 1.6)
		(legacy_teardrops no)
	)
	(paper "A4")
	(title_block
		(title "03242023_DA0F0TMBIJ0_F0T_Motherboard_J_brd_V01_OCP.brd")
		(comment 1 "Grand Teton / footprints 4416-4417 of 6105")
	)
	(layers
		(0 "F.Cu" signal "TOP")
		(4 "In1.Cu" signal "GND")
		(6 "In2.Cu" signal "IN1")
		(8 "In3.Cu" signal "GND1")
		(10 "In4.Cu" signal "IN2")
		(12 "In5.Cu" signal "GND2")
		(14 "In6.Cu" signal "IN3")
		(16 "In7.Cu" signal "GND3")
		(18 "In8.Cu" signal "VCC")
		(20 "In9.Cu" signal "VCC1")
		(22 "In10.Cu" signal "GND4")
		(24 "In11.Cu" signal "IN4")
		(26 "In12.Cu" signal "GND5")
		(28 "In13.Cu" signal "IN5")
		(30 "In14.Cu" signal "GND6")
		(32 "In15.Cu" signal "IN6")
		(34 "In16.Cu" signal "GND7")
		(2 "B.Cu" signal "BOTTOM")
		(9 "F.Adhes" user "F.Adhesive")
		(11 "B.Adhes" user "B.Adhesive")
		(13 "F.Paste" user "Package Geometry/Pastemask Top")
		(15 "B.Paste" user "Package Geometry/Pastemask Bottom")
		(5 "F.SilkS" user "Ref Des/Silkscreen Top")
		(7 "B.SilkS" user "Ref Des/Silkscreen Bottom")
		(1 "F.Mask" user "Board Geometry/Soldermask Top")
		(3 "B.Mask" user "Board Geometry/Soldermask Bottom")
		(17 "Dwgs.User" user "User.Drawings")
		(19 "Cmts.User" user "User.Comments")
		(21 "Eco1.User" user "User.Eco1")
		(23 "Eco2.User" user "User.Eco2")
		(25 "Edge.Cuts" user "Board Geometry/Outline")
		(27 "Margin" user)
		(31 "F.CrtYd" user "Package Geometry/Place Bound Top")
		(29 "B.CrtYd" user "Package Geometry/Place Bound Bottom")
		(35 "F.Fab" user "Ref Des/Assembly Top")
		(33 "B.Fab" user "Ref Des/Assembly Bottom")
	)
	(footprint ""
		(layer "B.Cu")
		(at 450.542914 -8.344916 90)
		(property "Reference" "R414"
			(at 0 0 90)
			(layer "B.SilkS")
			(hide yes)
			(effects
				(font
					(size 1.27 1.27)
				)
				(justify mirror)
			)
		)
		(property "Value" ""
			(at 0 0 90)
			(layer "B.Fab")
			(effects
				(font
					(size 1.27 1.27)
				)
				(justify mirror)
			)
		)
		(duplicate_pad_numbers_are_jumpers no)
		(fp_line
			(start 0.7874 -0.4064)
			(end -0.7874 -0.4064)
			(stroke
				(width 0.1524)
				(type default)
			)
			(layer "B.SilkS")
		)
		(fp_line
			(start -0.7874 -0.4064)
			(end -0.7874 0.4064)
			(stroke
				(width 0.1524)
				(type default)
			)
			(layer "B.SilkS")
		)
		(fp_line
			(start 0.7874 0.4064)
			(end 0.7874 -0.4064)
			(stroke
				(width 0.1524)
				(type default)
			)
			(layer "B.SilkS")
		)
		(fp_line
			(start -0.7874 0.4064)
			(end 0.7874 0.4064)
			(stroke
				(width 0.1524)
				(type default)
			)
			(layer "B.SilkS")
		)
		(fp_line
			(start 0.67945 -0.305054)
			(end 0.12065 -0.305054)
			(stroke
				(width 0.1)
				(type default)
			)
			(layer "B.Fab")
		)
		(fp_line
			(start 0.12065 -0.305054)
			(end 0.12065 -0.2794)
			(stroke
				(width 0.1)
				(type default)
			)
			(layer "B.Fab")
		)
		(fp_line
			(start -0.12065 -0.3048)
			(end -0.67945 -0.3048)
			(stroke
				(width 0.1)
				(type default)
			)
			(layer "B.Fab")
		)
		(fp_line
			(start -0.67945 -0.3048)
			(end -0.67945 0.3048)
			(stroke
				(width 0.1)
				(type default)
			)
			(layer "B.Fab")
		)
		(fp_line
			(start 0.12065 -0.2794)
			(end -0.12065 -0.2794)
			(stroke
				(width 0.1)
				(type default)
			)
			(layer "B.Fab")
		)
		(fp_line
			(start -0.12065 -0.2794)
			(end -0.12065 -0.3048)
			(stroke
				(width 0.1)
				(type default)
			)
			(layer "B.Fab")
		)
		(fp_line
			(start 0.12065 0.2794)
			(end 0.12065 0.3048)
			(stroke
				(width 0.1)
				(type default)
			)
			(layer "B.Fab")
		)
		(fp_line
			(start -0.120396 0.2794)
			(end 0.12065 0.2794)
			(stroke
				(width 0.1)
				(type default)
			)
			(layer "B.Fab")
		)
		(fp_line
			(start 0.67945 0.3048)
			(end 0.67945 -0.305054)
			(stroke
				(width 0.1)
				(type default)
			)
			(layer "B.Fab")
		)
		(fp_line
			(start 0.12065 0.3048)
			(end 0.67945 0.3048)
			(stroke
				(width 0.1)
				(type default)
			)
			(layer "B.Fab")
		)
		(fp_line
			(start -0.120396 0.3048)
			(end -0.120396 0.2794)
			(stroke
				(width 0.1)
				(type default)
			)
			(layer "B.Fab")
		)
		(fp_line
			(start -0.67945 0.3048)
			(end -0.120396 0.3048)
			(stroke
				(width 0.1)
				(type default)
			)
			(layer "B.Fab")
		)
		(pad "1" smd circle
			(at 0.40005 0 270)
			(size 0 0)
			(layers "B.Cu" "B.Mask" "B.Paste")
			(net "P3V3_OCP_SFF")
		)
		(pad "2" smd circle
			(at -0.40005 0 270)
			(size 0 0)
			(layers "B.Cu" "B.Mask" "B.Paste")
			(net "OCP_SFF_ID1")
		)
	)
	(footprint ""
		(layer "B.Cu")
		(at 81.446624 -185.874152 90)
		(property "Reference" "R198"
			(at 0 0 90)
			(layer "B.SilkS")
			(hide yes)
			(effects
				(font
					(size 1.27 1.27)
				)
				(justify mirror)
			)
		)
		(property "Value" ""
			(at 0 0 90)
			(layer "B.Fab")
			(effects
				(font
					(size 1.27 1.27)
				)
				(justify mirror)
			)
		)
		(duplicate_pad_numbers_are_jumpers no)
		(fp_line
			(start 0.7874 -0.4064)
			(end -0.7874 -0.4064)
			(stroke
				(width 0.1524)
				(type default)
			)
			(layer "B.SilkS")
		)
		(fp_line
			(start -0.7874 -0.4064)
			(end -0.7874 0.4064)
			(stroke
				(width 0.1524)
				(type default)
			)
			(layer "B.SilkS")
		)
		(fp_line
			(start 0.7874 0.4064)
			(end 0.7874 -0.4064)
			(stroke
				(width 0.1524)
				(type default)
			)
			(layer "B.SilkS")
		)
		(fp_line
			(start -0.7874 0.4064)
			(end 0.7874 0.4064)
			(stroke
				(width 0.1524)
				(type default)
			)
			(layer "B.SilkS")
		)
		(fp_line
			(start 0.67945 -0.305054)
			(end 0.12065 -0.305054)
			(stroke
				(width 0.1)
				(type default)
			)
			(layer "B.Fab")
		)
		(fp_line
			(start 0.12065 -0.305054)
			(end 0.12065 -0.2794)
			(stroke
				(width 0.1)
				(type default)
			)
			(layer "B.Fab")
		)
		(fp_line
			(start -0.12065 -0.3048)
			(end -0.67945 -0.3048)
			(stroke
				(width 0.1)
				(type default)
			)
			(layer "B.Fab")
		)
		(fp_line
			(start -0.67945 -0.3048)
			(end -0.67945 0.3048)
			(stroke
				(width 0.1)
				(type default)
			)
			(layer "B.Fab")
		)
		(fp_line
			(start 0.12065 -0.2794)
			(end -0.12065 -0.2794)
			(stroke
				(width 0.1)
				(type default)
			)
			(layer "B.Fab")
		)
		(fp_line
			(start -0.12065 -0.2794)
			(end -0.12065 -0.3048)
			(stroke
				(width 0.1)
				(type default)
			)
			(layer "B.Fab")
		)
		(fp_line
			(start 0.12065 0.2794)
			(end 0.12065 0.3048)
			(stroke
				(width 0.1)
				(type default)
			)
			(layer "B.Fab")
		)
		(fp_line
			(start -0.120396 0.2794)
			(end 0.12065 0.2794)
			(stroke
				(width 0.1)
				(type default)
			)
			(layer "B.Fab")
		)
		(fp_line
			(start 0.67945 0.3048)
			(end 0.67945 -0.305054)
			(stroke
				(width 0.1)
				(type default)
			)
			(layer "B.Fab")
		)
		(fp_line
			(start 0.12065 0.3048)
			(end 0.67945 0.3048)
			(stroke
				(width 0.1)
				(type default)
			)
			(layer "B.Fab")
		)
		(fp_line
			(start -0.120396 0.3048)
			(end -0.120396 0.2794)
			(stroke
				(width 0.1)
				(type default)
			)
			(layer "B.Fab")
		)
		(fp_line
			(start -0.67945 0.3048)
			(end -0.120396 0.3048)
			(stroke
				(width 0.1)
				(type default)
			)
			(layer "B.Fab")
		)
		(pad "1" smd circle
			(at 0.40005 0 270)
			(size 0 0)
			(layers "B.Cu" "B.Mask" "B.Paste")
			(net "PVNN_TERM_CPU1")
		)
		(pad "2" smd circle
			(at -0.40005 0 270)
			(size 0 0)
			(layers "B.Cu" "B.Mask" "B.Paste")
			(net "H_CPU1_NMI_LVC1_N")
		)
	)
)
